# T6G (Grand Teton) — schematic netlist excerpt (pin names and nets, part order shuffled) for the footprints in the layout excerpt that follows; sources: Cadence DE-HDL packaged netlist, KiCad conversion of 04192023_DAF0TMB3IC0_F0TG_MB_C_brd_V02_OCP.brd

C1055  Q_CAP  0.1UF 10V 10% X7S  pkg C0201  page 312 : A = P0V9_CPU0_RT3_2A ; B = GND
R8225  Q_RES  1K 1% EMPTY  pkg 0402LF  page 217 : A = PVDD18_S5_P1 ; B = SVID_PVDDCR_CPU1_P1_SVC_R
C575  Q_CAP  22UF 4V 20% X6S  pkg C0402  page 279 : A = P0V9_CPU0_RT0_2A ; B = GND

(kicad_pcb
	(version 20260206)
	(generator "pcbnew")
	(generator_version "10.0")
	(general
		(thickness 1.6)
		(legacy_teardrops no)
	)
	(paper "A4")
	(title_block
		(title "04192023_DAF0TMB3IC0_F0TG_MB_C_brd_V02_OCP.brd")
		(comment 1 "Grand Teton / footprints 8252-8254 of 8354")
	)
	(layers
		(0 "F.Cu" signal "TOP")
		(4 "In1.Cu" signal "GND")
		(6 "In2.Cu" signal "IN1")
		(8 "In3.Cu" signal "GND1")
		(10 "In4.Cu" signal "IN2")
		(12 "In5.Cu" signal "GND2")
		(14 "In6.Cu" signal "IN3")
		(16 "In7.Cu" signal "GND3")
		(18 "In8.Cu" signal "VCC")
		(20 "In9.Cu" signal "VCC1")
		(22 "In10.Cu" signal "GND4")
		(24 "In11.Cu" signal "IN4")
		(26 "In12.Cu" signal "GND5")
		(28 "In13.Cu" signal "IN5")
		(30 "In14.Cu" signal "GND6")
		(32 "In15.Cu" signal "IN6")
		(34 "In16.Cu" signal "GND7")
		(2 "B.Cu" signal "BOTTOM")
		(9 "F.Adhes" user "F.Adhesive")
		(11 "B.Adhes" user "B.Adhesive")
		(13 "F.Paste" user "Package Geometry/Pastemask Top")
		(15 "B.Paste" user "Package Geometry/Pastemask Bottom")
		(5 "F.SilkS" user "Ref Des/Silkscreen Top")
		(7 "B.SilkS" user "Ref Des/Silkscreen Bottom")
		(1 "F.Mask" user "Board Geometry/Soldermask Top")
		(3 "B.Mask" user "Board Geometry/Soldermask Bottom")
		(17 "Dwgs.User" user "User.Drawings")
		(19 "Cmts.User" user "User.Comments")
		(21 "Eco1.User" user "User.Eco1")
		(23 "Eco2.User" user "User.Eco2")
		(25 "Edge.Cuts" user "Board Geometry/Outline")
		(27 "Margin" user)
		(31 "F.CrtYd" user "Package Geometry/Place Bound Top")
		(29 "B.CrtYd" user "Package Geometry/Place Bound Bottom")
		(35 "F.Fab" user "Ref Des/Assembly Top")
		(33 "B.Fab" user "Ref Des/Assembly Bottom")
	)
	(footprint ""
		(layer "B.Cu")
		(at 322.7451 -398.942052 90)
		(property "Reference" "C575"
			(at 0 0 90)
			(layer "B.SilkS")
			(hide yes)
			(effects
				(font
					(size 1.27 1.27)
				)
				(justify mirror)
			)
		)
		(property "Value" ""
			(at 0 0 90)
			(layer "B.Fab")
			(effects
				(font
					(size 1.27 1.27)
				)
				(justify mirror)
			)
		)
		(duplicate_pad_numbers_are_jumpers no)
		(fp_line
			(start 0.7874 -0.4064)
			(end -0.7874 -0.4064)
			(stroke
				(width 0.1524)
				(type default)
			)
			(layer "B.SilkS")
		)
		(fp_line
			(start -0.7874 -0.4064)
			(end -0.7874 0.4064)
			(stroke
				(width 0.1524)
				(type default)
			)
			(layer "B.SilkS")
		)
		(fp_line
			(start 0.7874 0.4064)
			(end 0.7874 -0.4064)
			(stroke
				(width 0.1524)
				(type default)
			)
			(layer "B.SilkS")
		)
		(fp_line
			(start -0.7874 0.4064)
			(end 0.7874 0.4064)
			(stroke
				(width 0.1524)
				(type default)
			)
			(layer "B.SilkS")
		)
		(fp_line
			(start 0.67945 -0.305054)
			(end 0.12065 -0.305054)
			(stroke
				(width 0.1)
				(type default)
			)
			(layer "B.Fab")
		)
		(fp_line
			(start 0.12065 -0.305054)
			(end 0.12065 -0.2794)
			(stroke
				(width 0.1)
				(type default)
			)
			(layer "B.Fab")
		)
		(fp_line
			(start -0.12065 -0.3048)
			(end -0.67945 -0.3048)
			(stroke
				(width 0.1)
				(type default)
			)
			(layer "B.Fab")
		)
		(fp_line
			(start -0.67945 -0.3048)
			(end -0.67945 0.3048)
			(stroke
				(width 0.1)
				(type default)
			)
			(layer "B.Fab")
		)
		(fp_line
			(start 0.12065 -0.2794)
			(end -0.12065 -0.2794)
			(stroke
				(width 0.1)
				(type default)
			)
			(layer "B.Fab")
		)
		(fp_line
			(start -0.12065 -0.2794)
			(end -0.12065 -0.3048)
			(stroke
				(width 0.1)
				(type default)
			)
			(layer "B.Fab")
		)
		(fp_line
			(start 0.12065 0.2794)
			(end 0.12065 0.3048)
			(stroke
				(width 0.1)
				(type default)
			)
			(layer "B.Fab")
		)
		(fp_line
			(start -0.120396 0.2794)
			(end 0.12065 0.2794)
			(stroke
				(width 0.1)
				(type default)
			)
			(layer "B.Fab")
		)
		(fp_line
			(start 0.67945 0.3048)
			(end 0.67945 -0.305054)
			(stroke
				(width 0.1)
				(type default)
			)
			(layer "B.Fab")
		)
		(fp_line
			(start 0.12065 0.3048)
			(end 0.67945 0.3048)
			(stroke
				(width 0.1)
				(type default)
			)
			(layer "B.Fab")
		)
		(fp_line
			(start -0.120396 0.3048)
			(end -0.120396 0.2794)
			(stroke
				(width 0.1)
				(type default)
			)
			(layer "B.Fab")
		)
		(fp_line
			(start -0.67945 0.3048)
			(end -0.120396 0.3048)
			(stroke
				(width 0.1)
				(type default)
			)
			(layer "B.Fab")
		)
		(pad "1" smd circle
			(at 0.40005 0 270)
			(size 0 0)
			(layers "B.Cu" "B.Mask" "B.Paste")
			(net "P0V9_CPU0_RT0_2A")
		)
		(pad "2" smd circle
			(at -0.40005 0 270)
			(size 0 0)
			(layers "B.Cu" "B.Mask" "B.Paste")
			(net "GND")
		)
	)
	(footprint ""
		(layer "B.Cu")
		(at 385.018534 -396.393162 -90)
		(property "Reference" "C1055"
			(at 0 0 90)
			(layer "B.SilkS")
			(hide yes)
			(effects
				(font
					(size 1.27 1.27)
				)
				(justify mirror)
			)
		)
		(property "Value" ""
			(at 0 0 90)
			(layer "B.Fab")
			(effects
				(font
					(size 1.27 1.27)
				)
				(justify mirror)
			)
		)
		(duplicate_pad_numbers_are_jumpers no)
		(fp_line
			(start -0.299974 0.150114)
			(end 0.299974 0.150114)
			(stroke
				(width 0.1)
				(type default)
			)
			(layer "B.Fab")
		)
		(fp_line
			(start 0.299974 0.150114)
			(end 0.299974 -0.150114)
			(stroke
				(width 0.1)
				(type default)
			)
			(layer "B.Fab")
		)
		(fp_line
			(start -0.299974 -0.150114)
			(end -0.299974 0.150114)
			(stroke
				(width 0.1)
				(type default)
			)
			(layer "B.Fab")
		)
		(fp_line
			(start 0.299974 -0.150114)
			(end -0.299974 -0.150114)
			(stroke
				(width 0.1)
				(type default)
			)
			(layer "B.Fab")
		)
		(pad "1" smd rect
			(at 0.2667 0 90)
			(size 0.3048 0.381)
			(layers "B.Cu" "B.Mask" "B.Paste")
			(net "P0V9_CPU0_RT3_2A")
		)
		(pad "2" smd rect
			(at -0.2667 0 90)
			(size 0.3048 0.381)
			(layers "B.Cu" "B.Mask" "B.Paste")
			(net "GND")
		)
	)
	(footprint ""
		(layer "B.Cu")
		(at 22.479 -359.918 180)
		(property "Reference" "R8225"
			(at 0 0 0)
			(layer "B.SilkS")
			(hide yes)
			(effects
				(font
					(size 1.27 1.27)
				)
				(justify mirror)
			)
		)
		(property "Value" ""
			(at 0 0 0)
			(layer "B.Fab")
			(effects
				(font
					(size 1.27 1.27)
				)
				(justify mirror)
			)
		)
		(duplicate_pad_numbers_are_jumpers no)
		(fp_line
			(start 0.7874 0.4064)
			(end 0.7874 -0.4064)
			(stroke
				(width 0.1524)
				(type default)
			)
			(layer "B.SilkS")
		)
		(fp_line
			(start 0.7874 -0.4064)
			(end -0.7874 -0.4064)
			(stroke
				(width 0.1524)
				(type default)
			)
			(layer "B.SilkS")
		)
		(fp_line
			(start -0.7874 0.4064)
			(end 0.7874 0.4064)
			(stroke
				(width 0.1524)
				(type default)
			)
			(layer "B.SilkS")
		)
		(fp_line
			(start -0.7874 -0.4064)
			(end -0.7874 0.4064)
			(stroke
				(width 0.1524)
				(type default)
			)
			(layer "B.SilkS")
		)
		(fp_line
			(start 0.67945 0.3048)
			(end 0.67945 -0.305054)
			(stroke
				(width 0.1)
				(type default)
			)
			(layer "B.Fab")
		)
		(fp_line
			(start 0.67945 -0.305054)
			(end 0.12065 -0.305054)
			(stroke
				(width 0.1)
				(type default)
			)
			(layer "B.Fab")
		)
		(fp_line
			(start 0.12065 0.3048)
			(end 0.67945 0.3048)
			(stroke
				(width 0.1)
				(type default)
			)
			(layer "B.Fab")
		)
		(fp_line
			(start 0.12065 0.2794)
			(end 0.12065 0.3048)
			(stroke
				(width 0.1)
				(type default)
			)
			(layer "B.Fab")
		)
		(fp_line
			(start 0.12065 -0.2794)
			(end -0.12065 -0.2794)
			(stroke
				(width 0.1)
				(type default)
			)
			(layer "B.Fab")
		)
		(fp_line
			(start 0.12065 -0.305054)
			(end 0.12065 -0.2794)
			(stroke
				(width 0.1)
				(type default)
			)
			(layer "B.Fab")
		)
		(fp_line
			(start -0.120396 0.3048)
			(end -0.120396 0.2794)
			(stroke
				(width 0.1)
				(type default)
			)
			(layer "B.Fab")
		)
		(fp_line
			(start -0.120396 0.2794)
			(end 0.12065 0.2794)
			(stroke
				(width 0.1)
				(type default)
			)
			(layer "B.Fab")
		)
		(fp_line
			(start -0.12065 -0.2794)
			(end -0.12065 -0.3048)
			(stroke
				(width 0.1)
				(type default)
			)
			(layer "B.Fab")
		)
		(fp_line
			(start -0.12065 -0.3048)
			(end -0.67945 -0.3048)
			(stroke
				(width 0.1)
				(type default)
			)
			(layer "B.Fab")
		)
		(fp_line
			(start -0.67945 0.3048)
			(end -0.120396 0.3048)
			(stroke
				(width 0.1)
				(type default)
			)
			(layer "B.Fab")
		)
		(fp_line
			(start -0.67945 -0.3048)
			(end -0.67945 0.3048)
			(stroke
				(width 0.1)
				(type default)
			)
			(layer "B.Fab")
		)
		(pad "1" smd circle
			(at 0.40005 0)
			(size 0 0)
			(layers "B.Cu" "B.Mask" "B.Paste")
			(net "PVDD18_S5_P1")
		)
		(pad "2" smd circle
			(at -0.40005 0)
			(size 0 0)
			(layers "B.Cu" "B.Mask" "B.Paste")
			(net "SVID_PVDDCR_CPU1_P1_SVC_R")
		)
	)
)
